(kicad_pcb
	(version 20260206)
	(generator "pcbnew")
	(generator_version "10.0")
	(general
		(thickness 1.6)
		(legacy_teardrops no)
	)
	(paper "A4")
	(title_block
		(title "Wiwynn_Tioga_Pass_MB.brd")
		(comment 1 "Tioga Pass / footprint 2096 of 4770 (J4A2), pads 124-243 of 291")
	)
	(layers
		(0 "F.Cu" signal "TOP")
		(4 "In1.Cu" signal "L2GND")
		(6 "In2.Cu" signal "L3")
		(8 "In3.Cu" signal "L4GND")
		(10 "In4.Cu" signal "L5")
		(12 "In5.Cu" signal "L6GND")
		(14 "In6.Cu" signal "L7VCC")
		(16 "In7.Cu" signal "L8VCC")
		(18 "In8.Cu" signal "L9GND")
		(20 "In9.Cu" signal "L10")
		(22 "In10.Cu" signal "L11GND")
		(24 "In11.Cu" signal "L12")
		(26 "In12.Cu" signal "L13GND")
		(2 "B.Cu" signal "BOTTOM")
		(9 "F.Adhes" user "F.Adhesive")
		(11 "B.Adhes" user "B.Adhesive")
		(13 "F.Paste" user "Package Geometry/Pastemask Top")
		(15 "B.Paste" user "Package Geometry/Pastemask Bottom")
		(5 "F.SilkS" user "Ref Des/Silkscreen Top")
		(7 "B.SilkS" user "Ref Des/Silkscreen Bottom")
		(1 "F.Mask" user "Board Geometry/Soldermask Top")
		(3 "B.Mask" user "Board Geometry/Soldermask Bottom")
		(17 "Dwgs.User" user "User.Drawings")
		(19 "Cmts.User" user "User.Comments")
		(21 "Eco1.User" user "User.Eco1")
		(23 "Eco2.User" user "User.Eco2")
		(25 "Edge.Cuts" user "Board Geometry/Outline")
		(27 "Margin" user)
		(31 "F.CrtYd" user "Package Geometry/Place Bound Top")
		(29 "B.CrtYd" user "Package Geometry/Place Bound Bottom")
		(35 "F.Fab" user "Ref Des/Assembly Top")
		(33 "B.Fab" user "Ref Des/Assembly Bottom")
	)
	(footprint ""
		(layer "F.Cu")
		(at 194.700398 -142.6718 90)
		(property "Reference" "J4A2"
			(at -2.369312 42.66311 0)
			(unlocked yes)
			(layer "F.SilkS")
			(effects
				(font
					(size 0.7874 0.5842)
					(thickness 0.1524)
				)
				(justify left)
			)
		)
		(property "Value" ""
			(at 0 0 90)
			(layer "F.Fab")
			(effects
				(font
					(size 1.27 1.27)
				)
			)
		)
		(duplicate_pad_numbers_are_jumpers no)
		(pad "121" smd rect
			(at 0 107.100116 90)
			(size 1.8034 0.508)
			(layers "F.Cu" "F.Mask" "F.Paste")
			(net "M_E_DQS_DP<15>")
		)
		(pad "122" smd rect
			(at 0 107.95 90)
			(size 1.8034 0.508)
			(layers "F.Cu" "F.Mask" "F.Paste")
			(net "M_E_DQS_DN<15>")
		)
		(pad "123" smd rect
			(at 0 108.799884 90)
			(size 1.8034 0.508)
			(layers "F.Cu" "F.Mask" "F.Paste")
			(net "GND")
		)
		(pad "124" smd rect
			(at 0 109.650022 90)
			(size 1.8034 0.508)
			(layers "F.Cu" "F.Mask" "F.Paste")
			(net "M_E_DQ<55>")
		)
		(pad "125" smd rect
			(at 0 110.499906 90)
			(size 1.8034 0.508)
			(layers "F.Cu" "F.Mask" "F.Paste")
			(net "GND")
		)
		(pad "126" smd rect
			(at 0 111.350044 90)
			(size 1.8034 0.508)
			(layers "F.Cu" "F.Mask" "F.Paste")
			(net "M_E_DQ<51>")
		)
		(pad "127" smd rect
			(at 0 112.199928 90)
			(size 1.8034 0.508)
			(layers "F.Cu" "F.Mask" "F.Paste")
			(net "GND")
		)
		(pad "128" smd rect
			(at 0 113.050066 90)
			(size 1.8034 0.508)
			(layers "F.Cu" "F.Mask" "F.Paste")
			(net "M_E_DQ<61>")
		)
		(pad "129" smd rect
			(at 0 113.89995 90)
			(size 1.8034 0.508)
			(layers "F.Cu" "F.Mask" "F.Paste")
			(net "GND")
		)
		(pad "130" smd rect
			(at 0 114.750088 90)
			(size 1.8034 0.508)
			(layers "F.Cu" "F.Mask" "F.Paste")
			(net "M_E_DQ<57>")
		)
		(pad "131" smd rect
			(at 0 115.599972 90)
			(size 1.8034 0.508)
			(layers "F.Cu" "F.Mask" "F.Paste")
			(net "GND")
		)
		(pad "132" smd rect
			(at 0 116.45011 90)
			(size 1.8034 0.508)
			(layers "F.Cu" "F.Mask" "F.Paste")
			(net "M_E_DQS_DP<16>")
		)
		(pad "133" smd rect
			(at 0 117.299994 90)
			(size 1.8034 0.508)
			(layers "F.Cu" "F.Mask" "F.Paste")
			(net "M_E_DQS_DN<16>")
		)
		(pad "134" smd rect
			(at 0 118.149878 90)
			(size 1.8034 0.508)
			(layers "F.Cu" "F.Mask" "F.Paste")
			(net "GND")
		)
		(pad "135" smd rect
			(at 0 119.000016 90)
			(size 1.8034 0.508)
			(layers "F.Cu" "F.Mask" "F.Paste")
			(net "M_E_DQ<63>")
		)
		(pad "136" smd rect
			(at 0 119.8499 90)
			(size 1.8034 0.508)
			(layers "F.Cu" "F.Mask" "F.Paste")
			(net "GND")
		)
		(pad "137" smd rect
			(at 0 120.700038 90)
			(size 1.8034 0.508)
			(layers "F.Cu" "F.Mask" "F.Paste")
			(net "M_E_DQ<59>")
		)
		(pad "138" smd rect
			(at 0 121.549922 90)
			(size 1.8034 0.508)
			(layers "F.Cu" "F.Mask" "F.Paste")
			(net "GND")
		)
		(pad "139" smd rect
			(at 0 122.40006 90)
			(size 1.8034 0.508)
			(layers "F.Cu" "F.Mask" "F.Paste")
			(net "GND")
		)
		(pad "140" smd rect
			(at 0 123.249944 90)
			(size 1.8034 0.508)
			(layers "F.Cu" "F.Mask" "F.Paste")
			(net "PVPP_DEF")
		)
		(pad "141" smd rect
			(at 0 124.100082 90)
			(size 1.8034 0.508)
			(layers "F.Cu" "F.Mask" "F.Paste")
			(net "SMB_DDR_DEF_VPP_SCL")
		)
		(pad "142" smd rect
			(at 0 124.949966 90)
			(size 1.8034 0.508)
			(layers "F.Cu" "F.Mask" "F.Paste")
			(net "PVPP_DEF")
		)
		(pad "143" smd rect
			(at 0 125.800104 90)
			(size 1.8034 0.508)
			(layers "F.Cu" "F.Mask" "F.Paste")
			(net "PVPP_DEF")
		)
		(pad "144" smd rect
			(at 0 126.649988 90)
			(size 1.8034 0.508)
			(layers "F.Cu" "F.Mask" "F.Paste")
			(net "TP_CH_E_DIMM_E0_RFU_2")
		)
		(pad "145" smd rect
			(at 4.59994 0 90)
			(size 1.8034 0.508)
			(layers "F.Cu" "F.Mask" "F.Paste")
			(net "P12V_NVDIMM_DEF")
		)
		(pad "146" smd rect
			(at 4.59994 0.849884 90)
			(size 1.8034 0.508)
			(layers "F.Cu" "F.Mask" "F.Paste")
			(net "M_E_VREF")
		)
		(pad "147" smd rect
			(at 4.59994 1.700022 90)
			(size 1.8034 0.508)
			(layers "F.Cu" "F.Mask" "F.Paste")
			(net "GND")
		)
		(pad "148" smd rect
			(at 4.59994 2.549906 90)
			(size 1.8034 0.508)
			(layers "F.Cu" "F.Mask" "F.Paste")
			(net "M_E_DQ<4>")
		)
		(pad "149" smd rect
			(at 4.59994 3.400044 90)
			(size 1.8034 0.508)
			(layers "F.Cu" "F.Mask" "F.Paste")
			(net "GND")
		)
		(pad "150" smd rect
			(at 4.59994 4.249928 90)
			(size 1.8034 0.508)
			(layers "F.Cu" "F.Mask" "F.Paste")
			(net "M_E_DQ<0>")
		)
		(pad "151" smd rect
			(at 4.59994 5.100066 90)
			(size 1.8034 0.508)
			(layers "F.Cu" "F.Mask" "F.Paste")
			(net "GND")
		)
		(pad "152" smd rect
			(at 4.59994 5.94995 90)
			(size 1.8034 0.508)
			(layers "F.Cu" "F.Mask" "F.Paste")
			(net "M_E_DQS_DN<0>")
		)
		(pad "153" smd rect
			(at 4.59994 6.800088 90)
			(size 1.8034 0.508)
			(layers "F.Cu" "F.Mask" "F.Paste")
			(net "M_E_DQS_DP<0>")
		)
		(pad "154" smd rect
			(at 4.59994 7.649972 90)
			(size 1.8034 0.508)
			(layers "F.Cu" "F.Mask" "F.Paste")
			(net "GND")
		)
		(pad "155" smd rect
			(at 4.59994 8.50011 90)
			(size 1.8034 0.508)
			(layers "F.Cu" "F.Mask" "F.Paste")
			(net "M_E_DQ<6>")
		)
		(pad "156" smd rect
			(at 4.59994 9.349994 90)
			(size 1.8034 0.508)
			(layers "F.Cu" "F.Mask" "F.Paste")
			(net "GND")
		)
		(pad "157" smd rect
			(at 4.59994 10.199878 90)
			(size 1.8034 0.508)
			(layers "F.Cu" "F.Mask" "F.Paste")
			(net "M_E_DQ<2>")
		)
		(pad "158" smd rect
			(at 4.59994 11.050016 90)
			(size 1.8034 0.508)
			(layers "F.Cu" "F.Mask" "F.Paste")
			(net "GND")
		)
		(pad "159" smd rect
			(at 4.59994 11.8999 90)
			(size 1.8034 0.508)
			(layers "F.Cu" "F.Mask" "F.Paste")
			(net "M_E_DQ<12>")
		)
		(pad "160" smd rect
			(at 4.59994 12.750038 90)
			(size 1.8034 0.508)
			(layers "F.Cu" "F.Mask" "F.Paste")
			(net "GND")
		)
		(pad "161" smd rect
			(at 4.59994 13.599922 90)
			(size 1.8034 0.508)
			(layers "F.Cu" "F.Mask" "F.Paste")
			(net "M_E_DQ<8>")
		)
		(pad "162" smd rect
			(at 4.59994 14.45006 90)
			(size 1.8034 0.508)
			(layers "F.Cu" "F.Mask" "F.Paste")
			(net "GND")
		)
		(pad "163" smd rect
			(at 4.59994 15.299944 90)
			(size 1.8034 0.508)
			(layers "F.Cu" "F.Mask" "F.Paste")
			(net "M_E_DQS_DN<1>")
		)
		(pad "164" smd rect
			(at 4.59994 16.150082 90)
			(size 1.8034 0.508)
			(layers "F.Cu" "F.Mask" "F.Paste")
			(net "M_E_DQS_DP<1>")
		)
		(pad "165" smd rect
			(at 4.59994 16.999966 90)
			(size 1.8034 0.508)
			(layers "F.Cu" "F.Mask" "F.Paste")
			(net "GND")
		)
		(pad "166" smd rect
			(at 4.59994 17.850104 90)
			(size 1.8034 0.508)
			(layers "F.Cu" "F.Mask" "F.Paste")
			(net "M_E_DQ<14>")
		)
		(pad "167" smd rect
			(at 4.59994 18.699988 90)
			(size 1.8034 0.508)
			(layers "F.Cu" "F.Mask" "F.Paste")
			(net "GND")
		)
		(pad "168" smd rect
			(at 4.59994 19.550126 90)
			(size 1.8034 0.508)
			(layers "F.Cu" "F.Mask" "F.Paste")
			(net "M_E_DQ<10>")
		)
		(pad "169" smd rect
			(at 4.59994 20.40001 90)
			(size 1.8034 0.508)
			(layers "F.Cu" "F.Mask" "F.Paste")
			(net "GND")
		)
		(pad "170" smd rect
			(at 4.59994 21.249894 90)
			(size 1.8034 0.508)
			(layers "F.Cu" "F.Mask" "F.Paste")
			(net "M_E_DQ<20>")
		)
		(pad "171" smd rect
			(at 4.59994 22.100032 90)
			(size 1.8034 0.508)
			(layers "F.Cu" "F.Mask" "F.Paste")
			(net "GND")
		)
		(pad "172" smd rect
			(at 4.59994 22.949916 90)
			(size 1.8034 0.508)
			(layers "F.Cu" "F.Mask" "F.Paste")
			(net "M_E_DQ<16>")
		)
		(pad "173" smd rect
			(at 4.59994 23.800054 90)
			(size 1.8034 0.508)
			(layers "F.Cu" "F.Mask" "F.Paste")
			(net "GND")
		)
		(pad "174" smd rect
			(at 4.59994 24.649938 90)
			(size 1.8034 0.508)
			(layers "F.Cu" "F.Mask" "F.Paste")
			(net "M_E_DQS_DN<2>")
		)
		(pad "175" smd rect
			(at 4.59994 25.500076 90)
			(size 1.8034 0.508)
			(layers "F.Cu" "F.Mask" "F.Paste")
			(net "M_E_DQS_DP<2>")
		)
		(pad "176" smd rect
			(at 4.59994 26.34996 90)
			(size 1.8034 0.508)
			(layers "F.Cu" "F.Mask" "F.Paste")
			(net "GND")
		)
		(pad "177" smd rect
			(at 4.59994 27.200098 90)
			(size 1.8034 0.508)
			(layers "F.Cu" "F.Mask" "F.Paste")
			(net "M_E_DQ<22>")
		)
		(pad "178" smd rect
			(at 4.59994 28.049982 90)
			(size 1.8034 0.508)
			(layers "F.Cu" "F.Mask" "F.Paste")
			(net "GND")
		)
		(pad "179" smd rect
			(at 4.59994 28.90012 90)
			(size 1.8034 0.508)
			(layers "F.Cu" "F.Mask" "F.Paste")
			(net "M_E_DQ<18>")
		)
		(pad "180" smd rect
			(at 4.59994 29.750004 90)
			(size 1.8034 0.508)
			(layers "F.Cu" "F.Mask" "F.Paste")
			(net "GND")
		)
		(pad "181" smd rect
			(at 4.59994 30.599888 90)
			(size 1.8034 0.508)
			(layers "F.Cu" "F.Mask" "F.Paste")
			(net "M_E_DQ<28>")
		)
		(pad "182" smd rect
			(at 4.59994 31.450026 90)
			(size 1.8034 0.508)
			(layers "F.Cu" "F.Mask" "F.Paste")
			(net "GND")
		)
		(pad "183" smd rect
			(at 4.59994 32.29991 90)
			(size 1.8034 0.508)
			(layers "F.Cu" "F.Mask" "F.Paste")
			(net "M_E_DQ<24>")
		)
		(pad "184" smd rect
			(at 4.59994 33.150048 90)
			(size 1.8034 0.508)
			(layers "F.Cu" "F.Mask" "F.Paste")
			(net "GND")
		)
		(pad "185" smd rect
			(at 4.59994 33.999932 90)
			(size 1.8034 0.508)
			(layers "F.Cu" "F.Mask" "F.Paste")
			(net "M_E_DQS_DN<3>")
		)
		(pad "186" smd rect
			(at 4.59994 34.85007 90)
			(size 1.8034 0.508)
			(layers "F.Cu" "F.Mask" "F.Paste")
			(net "M_E_DQS_DP<3>")
		)
		(pad "187" smd rect
			(at 4.59994 35.699954 90)
			(size 1.8034 0.508)
			(layers "F.Cu" "F.Mask" "F.Paste")
			(net "GND")
		)
		(pad "188" smd rect
			(at 4.59994 36.550092 90)
			(size 1.8034 0.508)
			(layers "F.Cu" "F.Mask" "F.Paste")
			(net "M_E_DQ<30>")
		)
		(pad "189" smd rect
			(at 4.59994 37.399976 90)
			(size 1.8034 0.508)
			(layers "F.Cu" "F.Mask" "F.Paste")
			(net "GND")
		)
		(pad "190" smd rect
			(at 4.59994 38.250114 90)
			(size 1.8034 0.508)
			(layers "F.Cu" "F.Mask" "F.Paste")
			(net "M_E_DQ<26>")
		)
		(pad "191" smd rect
			(at 4.59994 39.099998 90)
			(size 1.8034 0.508)
			(layers "F.Cu" "F.Mask" "F.Paste")
			(net "GND")
		)
		(pad "192" smd rect
			(at 4.59994 39.949882 90)
			(size 1.8034 0.508)
			(layers "F.Cu" "F.Mask" "F.Paste")
			(net "M_E_ECC<4>")
		)
		(pad "193" smd rect
			(at 4.59994 40.80002 90)
			(size 1.8034 0.508)
			(layers "F.Cu" "F.Mask" "F.Paste")
			(net "GND")
		)
		(pad "194" smd rect
			(at 4.59994 41.649904 90)
			(size 1.8034 0.508)
			(layers "F.Cu" "F.Mask" "F.Paste")
			(net "M_E_ECC<0>")
		)
		(pad "195" smd rect
			(at 4.59994 42.500042 90)
			(size 1.8034 0.508)
			(layers "F.Cu" "F.Mask" "F.Paste")
			(net "GND")
		)
		(pad "196" smd rect
			(at 4.59994 43.349926 90)
			(size 1.8034 0.508)
			(layers "F.Cu" "F.Mask" "F.Paste")
			(net "M_E_DQS_DN<8>")
		)
		(pad "197" smd rect
			(at 4.59994 44.200064 90)
			(size 1.8034 0.508)
			(layers "F.Cu" "F.Mask" "F.Paste")
			(net "M_E_DQS_DP<8>")
		)
		(pad "198" smd rect
			(at 4.59994 45.049948 90)
			(size 1.8034 0.508)
			(layers "F.Cu" "F.Mask" "F.Paste")
			(net "GND")
		)
		(pad "199" smd rect
			(at 4.59994 45.900086 90)
			(size 1.8034 0.508)
			(layers "F.Cu" "F.Mask" "F.Paste")
			(net "M_E_ECC<6>")
		)
		(pad "200" smd rect
			(at 4.59994 46.74997 90)
			(size 1.8034 0.508)
			(layers "F.Cu" "F.Mask" "F.Paste")
			(net "GND")
		)
		(pad "201" smd rect
			(at 4.59994 47.600108 90)
			(size 1.8034 0.508)
			(layers "F.Cu" "F.Mask" "F.Paste")
			(net "M_E_ECC<2>")
		)
		(pad "202" smd rect
			(at 4.59994 48.449992 90)
			(size 1.8034 0.508)
			(layers "F.Cu" "F.Mask" "F.Paste")
			(net "GND")
		)
		(pad "203" smd rect
			(at 4.59994 49.299876 90)
			(size 1.8034 0.508)
			(layers "F.Cu" "F.Mask" "F.Paste")
			(net "M_E_CKE<1>")
		)
		(pad "204" smd rect
			(at 4.59994 50.150014 90)
			(size 1.8034 0.508)
			(layers "F.Cu" "F.Mask" "F.Paste")
			(net "PVDDQ_DEF")
		)
		(pad "205" smd rect
			(at 4.59994 50.999898 90)
			(size 1.8034 0.508)
			(layers "F.Cu" "F.Mask" "F.Paste")
			(net "TP_CH_E_DIMM_E0_RFU_0")
		)
		(pad "206" smd rect
			(at 4.59994 51.850036 90)
			(size 1.8034 0.508)
			(layers "F.Cu" "F.Mask" "F.Paste")
			(net "PVDDQ_DEF")
		)
		(pad "207" smd rect
			(at 4.59994 52.69992 90)
			(size 1.8034 0.508)
			(layers "F.Cu" "F.Mask" "F.Paste")
			(net "M_E_BG<1>")
		)
		(pad "208" smd rect
			(at 4.59994 53.550058 90)
			(size 1.8034 0.508)
			(layers "F.Cu" "F.Mask" "F.Paste")
			(net "M_E_ALERT_N")
		)
		(pad "209" smd rect
			(at 4.59994 54.399942 90)
			(size 1.8034 0.508)
			(layers "F.Cu" "F.Mask" "F.Paste")
			(net "PVDDQ_DEF")
		)
		(pad "210" smd rect
			(at 4.59994 55.25008 90)
			(size 1.8034 0.508)
			(layers "F.Cu" "F.Mask" "F.Paste")
			(net "M_E_MA<11>")
		)
		(pad "211" smd rect
			(at 4.59994 56.099964 90)
			(size 1.8034 0.508)
			(layers "F.Cu" "F.Mask" "F.Paste")
			(net "M_E_MA<7>")
		)
		(pad "212" smd rect
			(at 4.59994 56.950102 90)
			(size 1.8034 0.508)
			(layers "F.Cu" "F.Mask" "F.Paste")
			(net "PVDDQ_DEF")
		)
		(pad "213" smd rect
			(at 4.59994 57.799986 90)
			(size 1.8034 0.508)
			(layers "F.Cu" "F.Mask" "F.Paste")
			(net "M_E_MA<5>")
		)
		(pad "214" smd rect
			(at 4.59994 58.650124 90)
			(size 1.8034 0.508)
			(layers "F.Cu" "F.Mask" "F.Paste")
			(net "M_E_MA<4>")
		)
		(pad "215" smd rect
			(at 4.59994 59.500008 90)
			(size 1.8034 0.508)
			(layers "F.Cu" "F.Mask" "F.Paste")
			(net "PVDDQ_DEF")
		)
		(pad "216" smd rect
			(at 4.59994 60.349892 90)
			(size 1.8034 0.508)
			(layers "F.Cu" "F.Mask" "F.Paste")
			(net "M_E_MA<2>")
		)
		(pad "217" smd rect
			(at 4.59994 61.20003 90)
			(size 1.8034 0.508)
			(layers "F.Cu" "F.Mask" "F.Paste")
			(net "PVDDQ_DEF")
		)
		(pad "218" smd rect
			(at 4.59994 62.049914 90)
			(size 1.8034 0.508)
			(layers "F.Cu" "F.Mask" "F.Paste")
			(net "M_E_CLK_DP<1>")
		)
		(pad "219" smd rect
			(at 4.59994 62.900052 90)
			(size 1.8034 0.508)
			(layers "F.Cu" "F.Mask" "F.Paste")
			(net "M_E_CLK_DN<1>")
		)
		(pad "220" smd rect
			(at 4.59994 63.749936 90)
			(size 1.8034 0.508)
			(layers "F.Cu" "F.Mask" "F.Paste")
			(net "PVDDQ_DEF")
		)
		(pad "221" smd rect
			(at 4.59994 64.600074 90)
			(size 1.8034 0.508)
			(layers "F.Cu" "F.Mask" "F.Paste")
			(net "PVTT_DEF")
		)
		(pad "222" smd rect
			(at 4.59994 70.550024 90)
			(size 1.8034 0.508)
			(layers "F.Cu" "F.Mask" "F.Paste")
			(net "M_E_PAR")
		)
		(pad "223" smd rect
			(at 4.59994 71.399908 90)
			(size 1.8034 0.508)
			(layers "F.Cu" "F.Mask" "F.Paste")
			(net "PVDDQ_DEF")
		)
		(pad "224" smd rect
			(at 4.59994 72.250046 90)
			(size 1.8034 0.508)
			(layers "F.Cu" "F.Mask" "F.Paste")
			(net "M_E_BA<1>")
		)
		(pad "225" smd rect
			(at 4.59994 73.09993 90)
			(size 1.8034 0.508)
			(layers "F.Cu" "F.Mask" "F.Paste")
			(net "M_E_MA<10>")
		)
		(pad "226" smd rect
			(at 4.59994 73.950068 90)
			(size 1.8034 0.508)
			(layers "F.Cu" "F.Mask" "F.Paste")
			(net "PVDDQ_DEF")
		)
		(pad "227" smd rect
			(at 4.59994 74.799952 90)
			(size 1.8034 0.508)
			(layers "F.Cu" "F.Mask" "F.Paste")
			(net "TP_CH_E_DIMM_E0_RFU_1")
		)
		(pad "228" smd rect
			(at 4.59994 75.65009 90)
			(size 1.8034 0.508)
			(layers "F.Cu" "F.Mask" "F.Paste")
			(net "M_E_MA<14>")
		)
		(pad "229" smd rect
			(at 4.59994 76.499974 90)
			(size 1.8034 0.508)
			(layers "F.Cu" "F.Mask" "F.Paste")
			(net "PVDDQ_DEF")
		)
		(pad "230" smd rect
			(at 4.59994 77.350112 90)
			(size 1.8034 0.508)
			(layers "F.Cu" "F.Mask" "F.Paste")
			(net "FM_ADR_COMPLETE_DEF_N")
		)
		(pad "231" smd rect
			(at 4.59994 78.199996 90)
			(size 1.8034 0.508)
			(layers "F.Cu" "F.Mask" "F.Paste")
			(net "PVDDQ_DEF")
		)
		(pad "232" smd rect
			(at 4.59994 79.04988 90)
			(size 1.8034 0.508)
			(layers "F.Cu" "F.Mask" "F.Paste")
			(net "M_E_MA<13>")
		)
		(pad "233" smd rect
			(at 4.59994 79.900018 90)
			(size 1.8034 0.508)
			(layers "F.Cu" "F.Mask" "F.Paste")
			(net "PVDDQ_DEF")
		)
		(pad "234" smd rect
			(at 4.59994 80.749902 90)
			(size 1.8034 0.508)
			(layers "F.Cu" "F.Mask" "F.Paste")
			(net "M_E_MA<17>")
		)
		(pad "235" smd rect
			(at 4.59994 81.60004 90)
			(size 1.8034 0.508)
			(layers "F.Cu" "F.Mask" "F.Paste")
			(net "M_E_C<2>")
		)
		(pad "236" smd rect
			(at 4.59994 82.449924 90)
			(size 1.8034 0.508)
			(layers "F.Cu" "F.Mask" "F.Paste")
			(net "PVDDQ_DEF")
		)
		(pad "237" smd rect
			(at 4.59994 83.300062 90)
			(size 1.8034 0.508)
			(layers "F.Cu" "F.Mask" "F.Paste")
			(net "M_E_CS_N<3>")
		)
		(pad "238" smd rect
			(at 4.59994 84.149946 90)
			(size 1.8034 0.508)
			(layers "F.Cu" "F.Mask" "F.Paste")
			(net "GND")
		)
		(pad "239" smd rect
			(at 4.59994 85.000084 90)
			(size 1.8034 0.508)
			(layers "F.Cu" "F.Mask" "F.Paste")
			(net "GND")
		)
		(pad "240" smd rect
			(at 4.59994 85.849968 90)
			(size 1.8034 0.508)
			(layers "F.Cu" "F.Mask" "F.Paste")
			(net "M_E_DQ<36>")
		)
	)
)
